(kicad_pcb
	(version 20260206)
	(generator "pcbnew")
	(generator_version "10.0")
	(general
		(thickness 1.6)
		(legacy_teardrops no)
	)
	(paper "A4")
	(title_block
		(title "Wiwynn_Tioga_Pass_MB.brd")
		(comment 1 "Tioga Pass / footprints 659-666 of 4770")
	)
	(layers
		(0 "F.Cu" signal "TOP")
		(4 "In1.Cu" signal "L2GND")
		(6 "In2.Cu" signal "L3")
		(8 "In3.Cu" signal "L4GND")
		(10 "In4.Cu" signal "L5")
		(12 "In5.Cu" signal "L6GND")
		(14 "In6.Cu" signal "L7VCC")
		(16 "In7.Cu" signal "L8VCC")
		(18 "In8.Cu" signal "L9GND")
		(20 "In9.Cu" signal "L10")
		(22 "In10.Cu" signal "L11GND")
		(24 "In11.Cu" signal "L12")
		(26 "In12.Cu" signal "L13GND")
		(2 "B.Cu" signal "BOTTOM")
		(9 "F.Adhes" user "F.Adhesive")
		(11 "B.Adhes" user "B.Adhesive")
		(13 "F.Paste" user "Package Geometry/Pastemask Top")
		(15 "B.Paste" user "Package Geometry/Pastemask Bottom")
		(5 "F.SilkS" user "Ref Des/Silkscreen Top")
		(7 "B.SilkS" user "Ref Des/Silkscreen Bottom")
		(1 "F.Mask" user "Board Geometry/Soldermask Top")
		(3 "B.Mask" user "Board Geometry/Soldermask Bottom")
		(17 "Dwgs.User" user "User.Drawings")
		(19 "Cmts.User" user "User.Comments")
		(21 "Eco1.User" user "User.Eco1")
		(23 "Eco2.User" user "User.Eco2")
		(25 "Edge.Cuts" user "Board Geometry/Outline")
		(27 "Margin" user)
		(31 "F.CrtYd" user "Package Geometry/Place Bound Top")
		(29 "B.CrtYd" user "Package Geometry/Place Bound Bottom")
		(35 "F.Fab" user "Ref Des/Assembly Top")
		(33 "B.Fab" user "Ref Des/Assembly Bottom")
	)
	(footprint ""
		(layer "F.Cu")
		(at 392.049 -0.254)
		(property "Reference" "R8G10"
			(at 0 0 0)
			(layer "F.SilkS")
			(hide yes)
			(effects
				(font
					(size 1.27 1.27)
				)
			)
		)
		(property "Value" ""
			(at 0 0 0)
			(layer "F.Fab")
			(effects
				(font
					(size 1.27 1.27)
				)
			)
		)
		(duplicate_pad_numbers_are_jumpers no)
		(fp_poly
			(pts
				(xy -0.2794 -0.1016) (xy 0.2794 -0.1016) (xy 0.2794 0.9906) (xy -0.2794 0.9906)
			)
			(stroke
				(width 0)
				(type default)
			)
			(fill no)
			(layer "F.CrtYd")
		)
		(fp_line
			(start -0.2794 -0.1016)
			(end -0.2794 0.9906)
			(stroke
				(width 0.1)
				(type default)
			)
			(layer "F.Fab")
		)
		(fp_line
			(start -0.2794 0.9906)
			(end 0.2794 0.9906)
			(stroke
				(width 0.1)
				(type default)
			)
			(layer "F.Fab")
		)
		(fp_line
			(start 0.2794 -0.1016)
			(end -0.2794 -0.1016)
			(stroke
				(width 0.1)
				(type default)
			)
			(layer "F.Fab")
		)
		(fp_line
			(start 0.2794 0.9906)
			(end 0.2794 -0.1016)
			(stroke
				(width 0.1)
				(type default)
			)
			(layer "F.Fab")
		)
		(pad "1" smd rect
			(at 0 0)
			(size 0.508 0.508)
			(layers "F.Cu" "F.Mask" "F.Paste")
			(net "JTAG_BMC_TRST_N")
		)
		(pad "2" smd rect
			(at 0 0.889)
			(size 0.508 0.508)
			(layers "F.Cu" "F.Mask" "F.Paste")
			(net "JTAG_TRST_N")
		)
		(zone
			(layer "F.Cu")
			(hatch none 0.5)
			(connect_pads
				(clearance 0)
			)
			(min_thickness 0.25)
			(keepout
				(tracks allowed)
				(vias not_allowed)
				(pads allowed)
				(copperpour not_allowed)
				(footprints allowed)
			)
			(placement
				(enabled no)
				(sheetname "")
			)
			(fill
				(thermal_gap 0.5)
				(thermal_bridge_width 0.5)
				(island_removal_mode 0)
			)
			(polygon
				(pts
					(xy 391.795 0) (xy 392.303 0) (xy 392.303 0.381) (xy 391.795 0.381)
				)
			)
		)
		(zone
			(layer "F.Cu")
			(hatch none 0.5)
			(connect_pads
				(clearance 0)
			)
			(min_thickness 0.25)
			(keepout
				(tracks not_allowed)
				(vias allowed)
				(pads allowed)
				(copperpour not_allowed)
				(footprints allowed)
			)
			(placement
				(enabled no)
				(sheetname "")
			)
			(fill
				(thermal_gap 0.5)
				(thermal_bridge_width 0.5)
				(island_removal_mode 0)
			)
			(polygon
				(pts
					(xy 391.795 0.381) (xy 392.303 0.381) (xy 392.303 0) (xy 391.795 0)
				)
			)
		)
	)
	(footprint ""
		(layer "F.Cu")
		(at 480.842574 4.65709 90)
		(property "Reference" "C9G16"
			(at 0 0 90)
			(layer "F.SilkS")
			(hide yes)
			(effects
				(font
					(size 1.27 1.27)
				)
			)
		)
		(property "Value" ""
			(at 0 0 90)
			(layer "F.Fab")
			(effects
				(font
					(size 1.27 1.27)
				)
			)
		)
		(duplicate_pad_numbers_are_jumpers no)
		(fp_poly
			(pts
				(xy 0.3048 -0.1016) (xy 0.3048 0.9906) (xy -0.3048 0.9906) (xy -0.3048 -0.1016)
			)
			(stroke
				(width 0)
				(type default)
			)
			(fill no)
			(layer "F.CrtYd")
		)
		(fp_line
			(start 0.3048 -0.1016)
			(end -0.3048 -0.1016)
			(stroke
				(width 0.1)
				(type default)
			)
			(layer "F.Fab")
		)
		(fp_line
			(start -0.3048 -0.1016)
			(end -0.3048 0.9906)
			(stroke
				(width 0.1)
				(type default)
			)
			(layer "F.Fab")
		)
		(fp_line
			(start 0.3048 0.9906)
			(end 0.3048 -0.1016)
			(stroke
				(width 0.1)
				(type default)
			)
			(layer "F.Fab")
		)
		(fp_line
			(start -0.3048 0.9906)
			(end 0.3048 0.9906)
			(stroke
				(width 0.1)
				(type default)
			)
			(layer "F.Fab")
		)
		(pad "1" smd rect
			(at 0 0 90)
			(size 0.508 0.508)
			(layers "F.Cu" "F.Mask" "F.Paste")
			(net "NIC_SET_P_MDI_2_DP")
		)
		(pad "2" smd rect
			(at 0 0.889 90)
			(size 0.508 0.508)
			(layers "F.Cu" "F.Mask" "F.Paste")
			(net "NIC_MDI_MNG_TX_DP")
		)
		(zone
			(layer "F.Cu")
			(hatch none 0.5)
			(connect_pads
				(clearance 0)
			)
			(min_thickness 0.25)
			(keepout
				(tracks allowed)
				(vias not_allowed)
				(pads allowed)
				(copperpour not_allowed)
				(footprints allowed)
			)
			(placement
				(enabled no)
				(sheetname "")
			)
			(fill
				(thermal_gap 0.5)
				(thermal_bridge_width 0.5)
				(island_removal_mode 0)
			)
			(polygon
				(pts
					(xy 481.096574 4.91109) (xy 481.096574 4.40309) (xy 481.477574 4.40309) (xy 481.477574 4.91109)
				)
			)
		)
		(zone
			(layer "F.Cu")
			(hatch none 0.5)
			(connect_pads
				(clearance 0)
			)
			(min_thickness 0.25)
			(keepout
				(tracks not_allowed)
				(vias allowed)
				(pads allowed)
				(copperpour not_allowed)
				(footprints allowed)
			)
			(placement
				(enabled no)
				(sheetname "")
			)
			(fill
				(thermal_gap 0.5)
				(thermal_bridge_width 0.5)
				(island_removal_mode 0)
			)
			(polygon
				(pts
					(xy 481.477574 4.91109) (xy 481.477574 4.40309) (xy 481.096574 4.40309) (xy 481.096574 4.91109)
				)
			)
		)
	)
	(footprint ""
		(layer "F.Cu")
		(at 99.43084 -73.318116)
		(property "Reference" "C2D35"
			(at 0 0 0)
			(layer "F.SilkS")
			(hide yes)
			(effects
				(font
					(size 1.27 1.27)
				)
			)
		)
		(property "Value" ""
			(at 0 0 0)
			(layer "F.Fab")
			(effects
				(font
					(size 1.27 1.27)
				)
			)
		)
		(duplicate_pad_numbers_are_jumpers no)
		(fp_poly
			(pts
				(xy -0.4953 -0.2032) (xy 0.4953 -0.2032) (xy 0.4953 1.6002) (xy -0.4953 1.6002)
			)
			(stroke
				(width 0)
				(type default)
			)
			(fill no)
			(layer "F.CrtYd")
		)
		(fp_line
			(start -0.4953 -0.2032)
			(end 0.4953 -0.2032)
			(stroke
				(width 0.1)
				(type default)
			)
			(layer "F.Fab")
		)
		(fp_line
			(start -0.4953 1.6002)
			(end -0.4953 -0.2032)
			(stroke
				(width 0.1)
				(type default)
			)
			(layer "F.Fab")
		)
		(fp_line
			(start 0.4953 -0.2032)
			(end 0.4953 1.6002)
			(stroke
				(width 0.1)
				(type default)
			)
			(layer "F.Fab")
		)
		(fp_line
			(start 0.4953 1.6002)
			(end -0.4953 1.6002)
			(stroke
				(width 0.1)
				(type default)
			)
			(layer "F.Fab")
		)
		(pad "1" smd rect
			(at 0 0)
			(size 0.762 0.889)
			(layers "F.Cu" "F.Mask" "F.Paste")
			(net "PVCCIN_CPU1")
		)
		(pad "2" smd rect
			(at 0 1.397)
			(size 0.762 0.889)
			(layers "F.Cu" "F.Mask" "F.Paste")
			(net "GND")
		)
		(zone
			(layer "F.Cu")
			(hatch none 0.5)
			(connect_pads
				(clearance 0)
			)
			(min_thickness 0.25)
			(keepout
				(tracks not_allowed)
				(vias allowed)
				(pads allowed)
				(copperpour not_allowed)
				(footprints allowed)
			)
			(placement
				(enabled no)
				(sheetname "")
			)
			(fill
				(thermal_gap 0.5)
				(thermal_bridge_width 0.5)
				(island_removal_mode 0)
			)
			(polygon
				(pts
					(xy 99.04984 -72.873616) (xy 99.81184 -72.873616) (xy 99.81184 -72.365616) (xy 99.04984 -72.365616)
				)
			)
		)
	)
	(footprint ""
		(layer "F.Cu")
		(at 282.067 -76.835 -90)
		(property "Reference" "R6D5"
			(at 0 0 270)
			(layer "F.SilkS")
			(hide yes)
			(effects
				(font
					(size 1.27 1.27)
				)
			)
		)
		(property "Value" ""
			(at 0 0 270)
			(layer "F.Fab")
			(effects
				(font
					(size 1.27 1.27)
				)
			)
		)
		(duplicate_pad_numbers_are_jumpers no)
		(fp_rect
			(start 0.2794 0.9906)
			(end -0.2794 -0.1016)
			(stroke
				(width 0)
				(type default)
			)
			(fill no)
			(layer "F.CrtYd")
		)
		(fp_line
			(start -0.2794 0.9906)
			(end 0.2794 0.9906)
			(stroke
				(width 0.1)
				(type default)
			)
			(layer "F.Fab")
		)
		(fp_line
			(start 0.2794 0.9906)
			(end 0.2794 -0.1016)
			(stroke
				(width 0.1)
				(type default)
			)
			(layer "F.Fab")
		)
		(fp_line
			(start -0.2794 -0.1016)
			(end -0.2794 0.9906)
			(stroke
				(width 0.1)
				(type default)
			)
			(layer "F.Fab")
		)
		(fp_line
			(start 0.2794 -0.1016)
			(end -0.2794 -0.1016)
			(stroke
				(width 0.1)
				(type default)
			)
			(layer "F.Fab")
		)
		(pad "1" smd rect
			(at 0 0 270)
			(size 0.508 0.508)
			(layers "F.Cu" "F.Mask" "F.Paste")
			(net "PD_CPU0_TEST12")
		)
		(pad "2" smd rect
			(at 0 0.889 270)
			(size 0.508 0.508)
			(layers "F.Cu" "F.Mask" "F.Paste")
			(net "GND")
		)
		(zone
			(layer "F.Cu")
			(hatch none 0.5)
			(connect_pads
				(clearance 0)
			)
			(min_thickness 0.25)
			(keepout
				(tracks not_allowed)
				(vias allowed)
				(pads allowed)
				(copperpour not_allowed)
				(footprints allowed)
			)
			(placement
				(enabled no)
				(sheetname "")
			)
			(fill
				(thermal_gap 0.5)
				(thermal_bridge_width 0.5)
				(island_removal_mode 0)
			)
			(polygon
				(pts
					(xy 281.432 -76.581) (xy 281.813 -76.581) (xy 281.813 -77.089) (xy 281.432 -77.089)
				)
			)
		)
		(zone
			(layer "F.Cu")
			(hatch none 0.5)
			(connect_pads
				(clearance 0)
			)
			(min_thickness 0.25)
			(keepout
				(tracks allowed)
				(vias not_allowed)
				(pads allowed)
				(copperpour not_allowed)
				(footprints allowed)
			)
			(placement
				(enabled no)
				(sheetname "")
			)
			(fill
				(thermal_gap 0.5)
				(thermal_bridge_width 0.5)
				(island_removal_mode 0)
			)
			(polygon
				(pts
					(xy 281.432 -76.581) (xy 281.813 -76.581) (xy 281.813 -77.089) (xy 281.432 -77.089)
				)
			)
		)
	)
	(footprint ""
		(layer "F.Cu")
		(at 460.082392 -37.956998)
		(property "Reference" "C9F8"
			(at 0 0 0)
			(layer "F.SilkS")
			(hide yes)
			(effects
				(font
					(size 1.27 1.27)
				)
			)
		)
		(property "Value" ""
			(at 0 0 0)
			(layer "F.Fab")
			(effects
				(font
					(size 1.27 1.27)
				)
			)
		)
		(duplicate_pad_numbers_are_jumpers no)
		(fp_poly
			(pts
				(xy 0.3048 -0.1016) (xy 0.3048 0.9906) (xy -0.3048 0.9906) (xy -0.3048 -0.1016)
			)
			(stroke
				(width 0)
				(type default)
			)
			(fill no)
			(layer "F.CrtYd")
		)
		(fp_line
			(start -0.3048 -0.1016)
			(end -0.3048 0.9906)
			(stroke
				(width 0.1)
				(type default)
			)
			(layer "F.Fab")
		)
		(fp_line
			(start -0.3048 0.9906)
			(end 0.3048 0.9906)
			(stroke
				(width 0.1)
				(type default)
			)
			(layer "F.Fab")
		)
		(fp_line
			(start 0.3048 -0.1016)
			(end -0.3048 -0.1016)
			(stroke
				(width 0.1)
				(type default)
			)
			(layer "F.Fab")
		)
		(fp_line
			(start 0.3048 0.9906)
			(end 0.3048 -0.1016)
			(stroke
				(width 0.1)
				(type default)
			)
			(layer "F.Fab")
		)
		(pad "1" smd rect
			(at 0 0)
			(size 0.508 0.508)
			(layers "F.Cu" "F.Mask" "F.Paste")
			(net "PWRGD_P1V15_BMC_STBY_R")
		)
		(pad "2" smd rect
			(at 0 0.889)
			(size 0.508 0.508)
			(layers "F.Cu" "F.Mask" "F.Paste")
			(net "GND")
		)
		(zone
			(layer "F.Cu")
			(hatch none 0.5)
			(connect_pads
				(clearance 0)
			)
			(min_thickness 0.25)
			(keepout
				(tracks allowed)
				(vias not_allowed)
				(pads allowed)
				(copperpour not_allowed)
				(footprints allowed)
			)
			(placement
				(enabled no)
				(sheetname "")
			)
			(fill
				(thermal_gap 0.5)
				(thermal_bridge_width 0.5)
				(island_removal_mode 0)
			)
			(polygon
				(pts
					(xy 459.828392 -37.702998) (xy 460.336392 -37.702998) (xy 460.336392 -37.321998) (xy 459.828392 -37.321998)
				)
			)
		)
		(zone
			(layer "F.Cu")
			(hatch none 0.5)
			(connect_pads
				(clearance 0)
			)
			(min_thickness 0.25)
			(keepout
				(tracks not_allowed)
				(vias allowed)
				(pads allowed)
				(copperpour not_allowed)
				(footprints allowed)
			)
			(placement
				(enabled no)
				(sheetname "")
			)
			(fill
				(thermal_gap 0.5)
				(thermal_bridge_width 0.5)
				(island_removal_mode 0)
			)
			(polygon
				(pts
					(xy 459.828392 -37.321998) (xy 460.336392 -37.321998) (xy 460.336392 -37.702998) (xy 459.828392 -37.702998)
				)
			)
		)
	)
	(footprint ""
		(layer "F.Cu")
		(at 446.786 -16.002 90)
		(property "Reference" "R25W153"
			(at -0.8382 -0.67818 90)
			(unlocked yes)
			(layer "F.SilkS")
			(effects
				(font
					(size 0.4064 0.254)
					(thickness 0.1524)
				)
				(justify left)
			)
		)
		(property "Value" ""
			(at 0 0 90)
			(layer "F.Fab")
			(effects
				(font
					(size 1.27 1.27)
				)
			)
		)
		(duplicate_pad_numbers_are_jumpers no)
		(fp_poly
			(pts
				(xy -0.2794 -0.1016) (xy 0.2794 -0.1016) (xy 0.2794 0.9906) (xy -0.2794 0.9906)
			)
			(stroke
				(width 0)
				(type default)
			)
			(fill no)
			(layer "F.CrtYd")
		)
		(fp_line
			(start 0.2794 -0.1016)
			(end -0.2794 -0.1016)
			(stroke
				(width 0.1)
				(type default)
			)
			(layer "F.Fab")
		)
		(fp_line
			(start -0.2794 -0.1016)
			(end -0.2794 0.9906)
			(stroke
				(width 0.1)
				(type default)
			)
			(layer "F.Fab")
		)
		(fp_line
			(start 0.2794 0.9906)
			(end 0.2794 -0.1016)
			(stroke
				(width 0.1)
				(type default)
			)
			(layer "F.Fab")
		)
		(fp_line
			(start -0.2794 0.9906)
			(end 0.2794 0.9906)
			(stroke
				(width 0.1)
				(type default)
			)
			(layer "F.Fab")
		)
		(pad "1" smd rect
			(at 0 0 90)
			(size 0.508 0.508)
			(layers "F.Cu" "F.Mask" "F.Paste")
			(net "P3V3_STBY")
		)
		(pad "2" smd rect
			(at 0 0.889 90)
			(size 0.508 0.508)
			(layers "F.Cu" "F.Mask" "F.Paste")
			(net "RST_BMC_SRST_N")
		)
		(zone
			(layer "F.Cu")
			(hatch none 0.5)
			(connect_pads
				(clearance 0)
			)
			(min_thickness 0.25)
			(keepout
				(tracks allowed)
				(vias not_allowed)
				(pads allowed)
				(copperpour not_allowed)
				(footprints allowed)
			)
			(placement
				(enabled no)
				(sheetname "")
			)
			(fill
				(thermal_gap 0.5)
				(thermal_bridge_width 0.5)
				(island_removal_mode 0)
			)
			(polygon
				(pts
					(xy 447.04 -15.748) (xy 447.04 -16.256) (xy 447.421 -16.256) (xy 447.421 -15.748)
				)
			)
		)
		(zone
			(layer "F.Cu")
			(hatch none 0.5)
			(connect_pads
				(clearance 0)
			)
			(min_thickness 0.25)
			(keepout
				(tracks not_allowed)
				(vias allowed)
				(pads allowed)
				(copperpour not_allowed)
				(footprints allowed)
			)
			(placement
				(enabled no)
				(sheetname "")
			)
			(fill
				(thermal_gap 0.5)
				(thermal_bridge_width 0.5)
				(island_removal_mode 0)
			)
			(polygon
				(pts
					(xy 447.421 -15.748) (xy 447.421 -16.256) (xy 447.04 -16.256) (xy 447.04 -15.748)
				)
			)
		)
	)
	(footprint ""
		(layer "F.Cu")
		(at 88.392 -140.208 90)
		(property "Reference" "C2A12"
			(at 1.848866 0.752348 90)
			(unlocked yes)
			(layer "F.SilkS")
			(effects
				(font
					(size 1.27 0.9652)
					(thickness 0.1524)
				)
			)
		)
		(property "Value" ""
			(at 0 0 90)
			(layer "F.Fab")
			(effects
				(font
					(size 1.27 1.27)
				)
			)
		)
		(duplicate_pad_numbers_are_jumpers no)
		(fp_rect
			(start -0.500126 1.598422)
			(end 0.500126 -0.201422)
			(stroke
				(width 0)
				(type default)
			)
			(fill no)
			(layer "F.CrtYd")
		)
		(fp_line
			(start 0.500126 -0.201422)
			(end 0.500126 1.598422)
			(stroke
				(width 0.1)
				(type default)
			)
			(layer "F.Fab")
		)
		(fp_line
			(start -0.500126 -0.201422)
			(end 0.500126 -0.201422)
			(stroke
				(width 0.1)
				(type default)
			)
			(layer "F.Fab")
		)
		(fp_line
			(start 0.500126 1.598422)
			(end -0.500126 1.598422)
			(stroke
				(width 0.1)
				(type default)
			)
			(layer "F.Fab")
		)
		(fp_line
			(start -0.500126 1.598422)
			(end -0.500126 -0.201422)
			(stroke
				(width 0.1)
				(type default)
			)
			(layer "F.Fab")
		)
		(pad "1" smd rect
			(at 0 0)
			(size 0.889 0.9906)
			(layers "F.Cu" "F.Mask" "F.Paste")
			(net "PVDDQ_KLM")
		)
		(pad "2" smd rect
			(at 0 1.397)
			(size 0.889 0.9906)
			(layers "F.Cu" "F.Mask" "F.Paste")
			(net "GND")
		)
		(zone
			(layer "F.Cu")
			(hatch none 0.5)
			(connect_pads
				(clearance 0)
			)
			(min_thickness 0.25)
			(keepout
				(tracks not_allowed)
				(vias allowed)
				(pads allowed)
				(copperpour not_allowed)
				(footprints allowed)
			)
			(placement
				(enabled no)
				(sheetname "")
			)
			(fill
				(thermal_gap 0.5)
				(thermal_bridge_width 0.5)
				(island_removal_mode 0)
			)
			(polygon
				(pts
					(xy 89.3445 -139.7127) (xy 89.3445 -140.7033) (xy 88.8365 -140.7033) (xy 88.8365 -139.7127)
				)
			)
		)
		(zone
			(layer "F.Cu")
			(hatch none 0.5)
			(connect_pads
				(clearance 0)
			)
			(min_thickness 0.25)
			(keepout
				(tracks allowed)
				(vias not_allowed)
				(pads allowed)
				(copperpour not_allowed)
				(footprints allowed)
			)
			(placement
				(enabled no)
				(sheetname "")
			)
			(fill
				(thermal_gap 0.5)
				(thermal_bridge_width 0.5)
				(island_removal_mode 0)
			)
			(polygon
				(pts
					(xy 89.3445 -139.7127) (xy 89.3445 -140.7033) (xy 88.8365 -140.7033) (xy 88.8365 -139.7127)
				)
			)
		)
	)
	(footprint ""
		(layer "F.Cu")
		(at 161.723832 -71.43369)
		(property "Reference" "R3D18"
			(at 0 0 0)
			(layer "F.SilkS")
			(hide yes)
			(effects
				(font
					(size 1.27 1.27)
				)
			)
		)
		(property "Value" ""
			(at 0 0 0)
			(layer "F.Fab")
			(effects
				(font
					(size 1.27 1.27)
				)
			)
		)
		(duplicate_pad_numbers_are_jumpers no)
		(fp_poly
			(pts
				(xy -0.2794 -0.1016) (xy 0.2794 -0.1016) (xy 0.2794 0.9906) (xy -0.2794 0.9906)
			)
			(stroke
				(width 0)
				(type default)
			)
			(fill no)
			(layer "F.CrtYd")
		)
		(fp_line
			(start -0.2794 -0.1016)
			(end -0.2794 0.9906)
			(stroke
				(width 0.1)
				(type default)
			)
			(layer "F.Fab")
		)
		(fp_line
			(start -0.2794 0.9906)
			(end 0.2794 0.9906)
			(stroke
				(width 0.1)
				(type default)
			)
			(layer "F.Fab")
		)
		(fp_line
			(start 0.2794 -0.1016)
			(end -0.2794 -0.1016)
			(stroke
				(width 0.1)
				(type default)
			)
			(layer "F.Fab")
		)
		(fp_line
			(start 0.2794 0.9906)
			(end 0.2794 -0.1016)
			(stroke
				(width 0.1)
				(type default)
			)
			(layer "F.Fab")
		)
		(pad "1" smd rect
			(at 0 0)
			(size 0.508 0.508)
			(layers "F.Cu" "F.Mask" "F.Paste")
			(net "H_CPU0_FAST_WAKE_N")
		)
		(pad "2" smd rect
			(at 0 0.889)
			(size 0.508 0.508)
			(layers "F.Cu" "F.Mask" "F.Paste")
			(net "H_CPU1_FAST_WAKE_N")
		)
		(zone
			(layer "F.Cu")
			(hatch none 0.5)
			(connect_pads
				(clearance 0)
			)
			(min_thickness 0.25)
			(keepout
				(tracks allowed)
				(vias not_allowed)
				(pads allowed)
				(copperpour not_allowed)
				(footprints allowed)
			)
			(placement
				(enabled no)
				(sheetname "")
			)
			(fill
				(thermal_gap 0.5)
				(thermal_bridge_width 0.5)
				(island_removal_mode 0)
			)
			(polygon
				(pts
					(xy 161.469832 -71.17969) (xy 161.977832 -71.17969) (xy 161.977832 -70.79869) (xy 161.469832 -70.79869)
				)
			)
		)
		(zone
			(layer "F.Cu")
			(hatch none 0.5)
			(connect_pads
				(clearance 0)
			)
			(min_thickness 0.25)
			(keepout
				(tracks not_allowed)
				(vias allowed)
				(pads allowed)
				(copperpour not_allowed)
				(footprints allowed)
			)
			(placement
				(enabled no)
				(sheetname "")
			)
			(fill
				(thermal_gap 0.5)
				(thermal_bridge_width 0.5)
				(island_removal_mode 0)
			)
			(polygon
				(pts
					(xy 161.469832 -70.79869) (xy 161.977832 -70.79869) (xy 161.977832 -71.17969) (xy 161.469832 -71.17969)
				)
			)
		)
	)
)
